(kicad_pcb
	(version 20260206)
	(generator "pcbnew")
	(generator_version "10.0")
	(general
		(thickness 1.6)
		(legacy_teardrops no)
	)
	(paper "A4")
	(title_block
		(title "04192023_DAF0TMB3IC0_F0TG_MB_C_brd_V02_OCP.brd")
		(comment 1 "Grand Teton / footprints 2450-2456 of 8354")
	)
	(layers
		(0 "F.Cu" signal "TOP")
		(4 "In1.Cu" signal "GND")
		(6 "In2.Cu" signal "IN1")
		(8 "In3.Cu" signal "GND1")
		(10 "In4.Cu" signal "IN2")
		(12 "In5.Cu" signal "GND2")
		(14 "In6.Cu" signal "IN3")
		(16 "In7.Cu" signal "GND3")
		(18 "In8.Cu" signal "VCC")
		(20 "In9.Cu" signal "VCC1")
		(22 "In10.Cu" signal "GND4")
		(24 "In11.Cu" signal "IN4")
		(26 "In12.Cu" signal "GND5")
		(28 "In13.Cu" signal "IN5")
		(30 "In14.Cu" signal "GND6")
		(32 "In15.Cu" signal "IN6")
		(34 "In16.Cu" signal "GND7")
		(2 "B.Cu" signal "BOTTOM")
		(9 "F.Adhes" user "F.Adhesive")
		(11 "B.Adhes" user "B.Adhesive")
		(13 "F.Paste" user "Package Geometry/Pastemask Top")
		(15 "B.Paste" user "Package Geometry/Pastemask Bottom")
		(5 "F.SilkS" user "Ref Des/Silkscreen Top")
		(7 "B.SilkS" user "Ref Des/Silkscreen Bottom")
		(1 "F.Mask" user "Board Geometry/Soldermask Top")
		(3 "B.Mask" user "Board Geometry/Soldermask Bottom")
		(17 "Dwgs.User" user "User.Drawings")
		(19 "Cmts.User" user "User.Comments")
		(21 "Eco1.User" user "User.Eco1")
		(23 "Eco2.User" user "User.Eco2")
		(25 "Edge.Cuts" user "Board Geometry/Outline")
		(27 "Margin" user)
		(31 "F.CrtYd" user "Package Geometry/Place Bound Top")
		(29 "B.CrtYd" user "Package Geometry/Place Bound Bottom")
		(35 "F.Fab" user "Ref Des/Assembly Top")
		(33 "B.Fab" user "Ref Des/Assembly Bottom")
	)
	(footprint ""
		(layer "F.Cu")
		(at 74.969878 -389.344154 180)
		(property "Reference" "R1388"
			(at 0 0 180)
			(layer "F.SilkS")
			(hide yes)
			(effects
				(font
					(size 1.27 1.27)
				)
			)
		)
		(property "Value" ""
			(at 0 0 180)
			(layer "F.Fab")
			(effects
				(font
					(size 1.27 1.27)
				)
			)
		)
		(duplicate_pad_numbers_are_jumpers no)
		(fp_line
			(start 0.32512 0.175006)
			(end -0.32512 0.175006)
			(stroke
				(width 0.1)
				(type default)
			)
			(layer "F.Fab")
		)
		(fp_line
			(start 0.32512 -0.175006)
			(end 0.32512 0.175006)
			(stroke
				(width 0.1)
				(type default)
			)
			(layer "F.Fab")
		)
		(fp_line
			(start -0.32512 0.175006)
			(end -0.32512 -0.175006)
			(stroke
				(width 0.1)
				(type default)
			)
			(layer "F.Fab")
		)
		(fp_line
			(start -0.32512 -0.175006)
			(end 0.32512 -0.175006)
			(stroke
				(width 0.1)
				(type default)
			)
			(layer "F.Fab")
		)
		(pad "1" smd rect
			(at -0.2667 0 180)
			(size 0.3048 0.381)
			(layers "F.Cu" "F.Mask" "F.Paste")
			(net "P1V8_CPU1_RT_1D")
		)
		(pad "2" smd rect
			(at 0.2667 0)
			(size 0.3048 0.381)
			(layers "F.Cu" "F.Mask" "F.Paste")
			(net "RXDET_BYP_RT_CPU1_P0")
		)
	)
	(footprint ""
		(layer "F.Cu")
		(at 252.573536 -121.71045 180)
		(property "Reference" "R1498"
			(at 0 0 180)
			(layer "F.SilkS")
			(hide yes)
			(effects
				(font
					(size 1.27 1.27)
				)
			)
		)
		(property "Value" ""
			(at 0 0 180)
			(layer "F.Fab")
			(effects
				(font
					(size 1.27 1.27)
				)
			)
		)
		(duplicate_pad_numbers_are_jumpers no)
		(fp_line
			(start 0.7874 0.4064)
			(end -0.7874 0.4064)
			(stroke
				(width 0.1524)
				(type default)
			)
			(layer "F.SilkS")
		)
		(fp_line
			(start 0.7874 -0.4064)
			(end 0.7874 0.4064)
			(stroke
				(width 0.1524)
				(type default)
			)
			(layer "F.SilkS")
		)
		(fp_line
			(start -0.7874 0.4064)
			(end -0.7874 -0.4064)
			(stroke
				(width 0.1524)
				(type default)
			)
			(layer "F.SilkS")
		)
		(fp_line
			(start -0.7874 -0.4064)
			(end 0.7874 -0.4064)
			(stroke
				(width 0.1524)
				(type default)
			)
			(layer "F.SilkS")
		)
		(fp_line
			(start 0.67945 0.3048)
			(end 0.120396 0.3048)
			(stroke
				(width 0.1)
				(type default)
			)
			(layer "F.Fab")
		)
		(fp_line
			(start 0.67945 -0.3048)
			(end 0.67945 0.3048)
			(stroke
				(width 0.1)
				(type default)
			)
			(layer "F.Fab")
		)
		(fp_line
			(start 0.12065 -0.2794)
			(end 0.12065 -0.3048)
			(stroke
				(width 0.1)
				(type default)
			)
			(layer "F.Fab")
		)
		(fp_line
			(start 0.12065 -0.3048)
			(end 0.67945 -0.3048)
			(stroke
				(width 0.1)
				(type default)
			)
			(layer "F.Fab")
		)
		(fp_line
			(start 0.120396 0.3048)
			(end 0.120396 0.2794)
			(stroke
				(width 0.1)
				(type default)
			)
			(layer "F.Fab")
		)
		(fp_line
			(start 0.120396 0.2794)
			(end -0.12065 0.2794)
			(stroke
				(width 0.1)
				(type default)
			)
			(layer "F.Fab")
		)
		(fp_line
			(start -0.12065 0.3048)
			(end -0.67945 0.3048)
			(stroke
				(width 0.1)
				(type default)
			)
			(layer "F.Fab")
		)
		(fp_line
			(start -0.12065 0.2794)
			(end -0.12065 0.3048)
			(stroke
				(width 0.1)
				(type default)
			)
			(layer "F.Fab")
		)
		(fp_line
			(start -0.12065 -0.2794)
			(end 0.12065 -0.2794)
			(stroke
				(width 0.1)
				(type default)
			)
			(layer "F.Fab")
		)
		(fp_line
			(start -0.12065 -0.305054)
			(end -0.12065 -0.2794)
			(stroke
				(width 0.1)
				(type default)
			)
			(layer "F.Fab")
		)
		(fp_line
			(start -0.67945 0.3048)
			(end -0.67945 -0.305054)
			(stroke
				(width 0.1)
				(type default)
			)
			(layer "F.Fab")
		)
		(fp_line
			(start -0.67945 -0.305054)
			(end -0.12065 -0.305054)
			(stroke
				(width 0.1)
				(type default)
			)
			(layer "F.Fab")
		)
		(pad "1" smd circle
			(at -0.40005 0 180)
			(size 0 0)
			(layers "F.Cu" "F.Mask" "F.Paste")
			(net "SMB_VR_3V3AUX_SDA")
		)
		(pad "2" smd circle
			(at 0.40005 0 180)
			(size 0 0)
			(layers "F.Cu" "F.Mask" "F.Paste")
			(net "SMB_SCM_2_R3_SDA")
		)
	)
	(footprint ""
		(layer "F.Cu")
		(at 297.315128 -147.472908)
		(property "Reference" "R5006"
			(at 0 0 0)
			(layer "F.SilkS")
			(hide yes)
			(effects
				(font
					(size 1.27 1.27)
				)
			)
		)
		(property "Value" ""
			(at 0 0 0)
			(layer "F.Fab")
			(effects
				(font
					(size 1.27 1.27)
				)
			)
		)
		(duplicate_pad_numbers_are_jumpers no)
		(fp_line
			(start -0.7874 -0.4064)
			(end 0.7874 -0.4064)
			(stroke
				(width 0.1524)
				(type default)
			)
			(layer "F.SilkS")
		)
		(fp_line
			(start -0.7874 0.4064)
			(end -0.7874 -0.4064)
			(stroke
				(width 0.1524)
				(type default)
			)
			(layer "F.SilkS")
		)
		(fp_line
			(start 0.7874 -0.4064)
			(end 0.7874 0.4064)
			(stroke
				(width 0.1524)
				(type default)
			)
			(layer "F.SilkS")
		)
		(fp_line
			(start 0.7874 0.4064)
			(end -0.7874 0.4064)
			(stroke
				(width 0.1524)
				(type default)
			)
			(layer "F.SilkS")
		)
		(fp_line
			(start -0.67945 -0.305054)
			(end -0.12065 -0.305054)
			(stroke
				(width 0.1)
				(type default)
			)
			(layer "F.Fab")
		)
		(fp_line
			(start -0.67945 0.3048)
			(end -0.67945 -0.305054)
			(stroke
				(width 0.1)
				(type default)
			)
			(layer "F.Fab")
		)
		(fp_line
			(start -0.12065 -0.305054)
			(end -0.12065 -0.2794)
			(stroke
				(width 0.1)
				(type default)
			)
			(layer "F.Fab")
		)
		(fp_line
			(start -0.12065 -0.2794)
			(end 0.12065 -0.2794)
			(stroke
				(width 0.1)
				(type default)
			)
			(layer "F.Fab")
		)
		(fp_line
			(start -0.12065 0.2794)
			(end -0.12065 0.3048)
			(stroke
				(width 0.1)
				(type default)
			)
			(layer "F.Fab")
		)
		(fp_line
			(start -0.12065 0.3048)
			(end -0.67945 0.3048)
			(stroke
				(width 0.1)
				(type default)
			)
			(layer "F.Fab")
		)
		(fp_line
			(start 0.120396 0.2794)
			(end -0.12065 0.2794)
			(stroke
				(width 0.1)
				(type default)
			)
			(layer "F.Fab")
		)
		(fp_line
			(start 0.120396 0.3048)
			(end 0.120396 0.2794)
			(stroke
				(width 0.1)
				(type default)
			)
			(layer "F.Fab")
		)
		(fp_line
			(start 0.12065 -0.3048)
			(end 0.67945 -0.3048)
			(stroke
				(width 0.1)
				(type default)
			)
			(layer "F.Fab")
		)
		(fp_line
			(start 0.12065 -0.2794)
			(end 0.12065 -0.3048)
			(stroke
				(width 0.1)
				(type default)
			)
			(layer "F.Fab")
		)
		(fp_line
			(start 0.67945 -0.3048)
			(end 0.67945 0.3048)
			(stroke
				(width 0.1)
				(type default)
			)
			(layer "F.Fab")
		)
		(fp_line
			(start 0.67945 0.3048)
			(end 0.120396 0.3048)
			(stroke
				(width 0.1)
				(type default)
			)
			(layer "F.Fab")
		)
		(pad "1" smd circle
			(at -0.40005 0)
			(size 0 0)
			(layers "F.Cu" "F.Mask" "F.Paste")
			(net "PVDD11_S3_P0")
		)
		(pad "2" smd circle
			(at 0.40005 0)
			(size 0 0)
			(layers "F.Cu" "F.Mask" "F.Paste")
			(net "I3C_SPD_DDRAF_CPU0_LVC1_SCL")
		)
	)
	(footprint ""
		(layer "F.Cu")
		(at 463.465926 -97.523808)
		(property "Reference" "R2473"
			(at 0 0 0)
			(layer "F.SilkS")
			(hide yes)
			(effects
				(font
					(size 1.27 1.27)
				)
			)
		)
		(property "Value" ""
			(at 0 0 0)
			(layer "F.Fab")
			(effects
				(font
					(size 1.27 1.27)
				)
			)
		)
		(duplicate_pad_numbers_are_jumpers no)
		(fp_line
			(start -0.7874 -0.4064)
			(end 0.7874 -0.4064)
			(stroke
				(width 0.1524)
				(type default)
			)
			(layer "F.SilkS")
		)
		(fp_line
			(start -0.7874 0.4064)
			(end -0.7874 -0.4064)
			(stroke
				(width 0.1524)
				(type default)
			)
			(layer "F.SilkS")
		)
		(fp_line
			(start 0.7874 -0.4064)
			(end 0.7874 0.4064)
			(stroke
				(width 0.1524)
				(type default)
			)
			(layer "F.SilkS")
		)
		(fp_line
			(start 0.7874 0.4064)
			(end -0.7874 0.4064)
			(stroke
				(width 0.1524)
				(type default)
			)
			(layer "F.SilkS")
		)
		(fp_line
			(start -0.67945 -0.305054)
			(end -0.12065 -0.305054)
			(stroke
				(width 0.1)
				(type default)
			)
			(layer "F.Fab")
		)
		(fp_line
			(start -0.67945 0.3048)
			(end -0.67945 -0.305054)
			(stroke
				(width 0.1)
				(type default)
			)
			(layer "F.Fab")
		)
		(fp_line
			(start -0.12065 -0.305054)
			(end -0.12065 -0.2794)
			(stroke
				(width 0.1)
				(type default)
			)
			(layer "F.Fab")
		)
		(fp_line
			(start -0.12065 -0.2794)
			(end 0.12065 -0.2794)
			(stroke
				(width 0.1)
				(type default)
			)
			(layer "F.Fab")
		)
		(fp_line
			(start -0.12065 0.2794)
			(end -0.12065 0.3048)
			(stroke
				(width 0.1)
				(type default)
			)
			(layer "F.Fab")
		)
		(fp_line
			(start -0.12065 0.3048)
			(end -0.67945 0.3048)
			(stroke
				(width 0.1)
				(type default)
			)
			(layer "F.Fab")
		)
		(fp_line
			(start 0.120396 0.2794)
			(end -0.12065 0.2794)
			(stroke
				(width 0.1)
				(type default)
			)
			(layer "F.Fab")
		)
		(fp_line
			(start 0.120396 0.3048)
			(end 0.120396 0.2794)
			(stroke
				(width 0.1)
				(type default)
			)
			(layer "F.Fab")
		)
		(fp_line
			(start 0.12065 -0.3048)
			(end 0.67945 -0.3048)
			(stroke
				(width 0.1)
				(type default)
			)
			(layer "F.Fab")
		)
		(fp_line
			(start 0.12065 -0.2794)
			(end 0.12065 -0.3048)
			(stroke
				(width 0.1)
				(type default)
			)
			(layer "F.Fab")
		)
		(fp_line
			(start 0.67945 -0.3048)
			(end 0.67945 0.3048)
			(stroke
				(width 0.1)
				(type default)
			)
			(layer "F.Fab")
		)
		(fp_line
			(start 0.67945 0.3048)
			(end 0.120396 0.3048)
			(stroke
				(width 0.1)
				(type default)
			)
			(layer "F.Fab")
		)
		(pad "1" smd circle
			(at -0.40005 0)
			(size 0 0)
			(layers "F.Cu" "F.Mask" "F.Paste")
			(net "FB_BMC_ISOLATE_R1")
		)
		(pad "2" smd circle
			(at 0.40005 0)
			(size 0 0)
			(layers "F.Cu" "F.Mask" "F.Paste")
			(net "FB_BMC_ISOLATE")
		)
	)
	(footprint ""
		(layer "F.Cu")
		(at 114.926364 -167.2717 -90)
		(property "Reference" "PR209"
			(at 0 0 270)
			(layer "F.SilkS")
			(hide yes)
			(effects
				(font
					(size 1.27 1.27)
				)
			)
		)
		(property "Value" ""
			(at 0 0 270)
			(layer "F.Fab")
			(effects
				(font
					(size 1.27 1.27)
				)
			)
		)
		(duplicate_pad_numbers_are_jumpers no)
		(fp_line
			(start -0.7874 0.4064)
			(end -0.7874 -0.4064)
			(stroke
				(width 0.1524)
				(type default)
			)
			(layer "F.SilkS")
		)
		(fp_line
			(start 0.7874 0.4064)
			(end -0.7874 0.4064)
			(stroke
				(width 0.1524)
				(type default)
			)
			(layer "F.SilkS")
		)
		(fp_line
			(start -0.7874 -0.4064)
			(end 0.7874 -0.4064)
			(stroke
				(width 0.1524)
				(type default)
			)
			(layer "F.SilkS")
		)
		(fp_line
			(start 0.7874 -0.4064)
			(end 0.7874 0.4064)
			(stroke
				(width 0.1524)
				(type default)
			)
			(layer "F.SilkS")
		)
		(fp_line
			(start -0.67945 0.3048)
			(end -0.67945 -0.305054)
			(stroke
				(width 0.1)
				(type default)
			)
			(layer "F.Fab")
		)
		(fp_line
			(start -0.12065 0.3048)
			(end -0.67945 0.3048)
			(stroke
				(width 0.1)
				(type default)
			)
			(layer "F.Fab")
		)
		(fp_line
			(start 0.120396 0.3048)
			(end 0.120396 0.2794)
			(stroke
				(width 0.1)
				(type default)
			)
			(layer "F.Fab")
		)
		(fp_line
			(start 0.67945 0.3048)
			(end 0.120396 0.3048)
			(stroke
				(width 0.1)
				(type default)
			)
			(layer "F.Fab")
		)
		(fp_line
			(start -0.12065 0.2794)
			(end -0.12065 0.3048)
			(stroke
				(width 0.1)
				(type default)
			)
			(layer "F.Fab")
		)
		(fp_line
			(start 0.120396 0.2794)
			(end -0.12065 0.2794)
			(stroke
				(width 0.1)
				(type default)
			)
			(layer "F.Fab")
		)
		(fp_line
			(start -0.12065 -0.2794)
			(end 0.12065 -0.2794)
			(stroke
				(width 0.1)
				(type default)
			)
			(layer "F.Fab")
		)
		(fp_line
			(start 0.12065 -0.2794)
			(end 0.12065 -0.3048)
			(stroke
				(width 0.1)
				(type default)
			)
			(layer "F.Fab")
		)
		(fp_line
			(start 0.12065 -0.3048)
			(end 0.67945 -0.3048)
			(stroke
				(width 0.1)
				(type default)
			)
			(layer "F.Fab")
		)
		(fp_line
			(start 0.67945 -0.3048)
			(end 0.67945 0.3048)
			(stroke
				(width 0.1)
				(type default)
			)
			(layer "F.Fab")
		)
		(fp_line
			(start -0.67945 -0.305054)
			(end -0.12065 -0.305054)
			(stroke
				(width 0.1)
				(type default)
			)
			(layer "F.Fab")
		)
		(fp_line
			(start -0.12065 -0.305054)
			(end -0.12065 -0.2794)
			(stroke
				(width 0.1)
				(type default)
			)
			(layer "F.Fab")
		)
		(pad "1" smd circle
			(at -0.40005 0 270)
			(size 0 0)
			(layers "F.Cu" "F.Mask" "F.Paste")
			(net "SW_PVDDCR_SOC_P1_BOOT1")
		)
		(pad "2" smd circle
			(at 0.40005 0 270)
			(size 0 0)
			(layers "F.Cu" "F.Mask" "F.Paste")
			(net "SW_PVDDCR_SOC_P1_BOOT1_RC")
		)
	)
	(footprint ""
		(layer "F.Cu")
		(at 408.841702 -163.736274 -90)
		(property "Reference" "PC578_8"
			(at 0 0 270)
			(layer "F.SilkS")
			(hide yes)
			(effects
				(font
					(size 1.27 1.27)
				)
			)
		)
		(property "Value" ""
			(at 0 0 270)
			(layer "F.Fab")
			(effects
				(font
					(size 1.27 1.27)
				)
			)
		)
		(duplicate_pad_numbers_are_jumpers no)
		(fp_line
			(start -0.7874 0.4064)
			(end -0.7874 -0.4064)
			(stroke
				(width 0.1524)
				(type default)
			)
			(layer "F.SilkS")
		)
		(fp_line
			(start 0.7874 0.4064)
			(end -0.7874 0.4064)
			(stroke
				(width 0.1524)
				(type default)
			)
			(layer "F.SilkS")
		)
		(fp_line
			(start -0.7874 -0.4064)
			(end 0.7874 -0.4064)
			(stroke
				(width 0.1524)
				(type default)
			)
			(layer "F.SilkS")
		)
		(fp_line
			(start 0.7874 -0.4064)
			(end 0.7874 0.4064)
			(stroke
				(width 0.1524)
				(type default)
			)
			(layer "F.SilkS")
		)
		(fp_line
			(start -0.67945 0.3048)
			(end -0.67945 -0.305054)
			(stroke
				(width 0.1)
				(type default)
			)
			(layer "F.Fab")
		)
		(fp_line
			(start -0.12065 0.3048)
			(end -0.67945 0.3048)
			(stroke
				(width 0.1)
				(type default)
			)
			(layer "F.Fab")
		)
		(fp_line
			(start 0.120396 0.3048)
			(end 0.120396 0.2794)
			(stroke
				(width 0.1)
				(type default)
			)
			(layer "F.Fab")
		)
		(fp_line
			(start 0.67945 0.3048)
			(end 0.120396 0.3048)
			(stroke
				(width 0.1)
				(type default)
			)
			(layer "F.Fab")
		)
		(fp_line
			(start -0.12065 0.2794)
			(end -0.12065 0.3048)
			(stroke
				(width 0.1)
				(type default)
			)
			(layer "F.Fab")
		)
		(fp_line
			(start 0.120396 0.2794)
			(end -0.12065 0.2794)
			(stroke
				(width 0.1)
				(type default)
			)
			(layer "F.Fab")
		)
		(fp_line
			(start -0.12065 -0.2794)
			(end 0.12065 -0.2794)
			(stroke
				(width 0.1)
				(type default)
			)
			(layer "F.Fab")
		)
		(fp_line
			(start 0.12065 -0.2794)
			(end 0.12065 -0.3048)
			(stroke
				(width 0.1)
				(type default)
			)
			(layer "F.Fab")
		)
		(fp_line
			(start 0.12065 -0.3048)
			(end 0.67945 -0.3048)
			(stroke
				(width 0.1)
				(type default)
			)
			(layer "F.Fab")
		)
		(fp_line
			(start 0.67945 -0.3048)
			(end 0.67945 0.3048)
			(stroke
				(width 0.1)
				(type default)
			)
			(layer "F.Fab")
		)
		(fp_line
			(start -0.67945 -0.305054)
			(end -0.12065 -0.305054)
			(stroke
				(width 0.1)
				(type default)
			)
			(layer "F.Fab")
		)
		(fp_line
			(start -0.12065 -0.305054)
			(end -0.12065 -0.2794)
			(stroke
				(width 0.1)
				(type default)
			)
			(layer "F.Fab")
		)
		(pad "1" smd circle
			(at -0.40005 0 270)
			(size 0 0)
			(layers "F.Cu" "F.Mask" "F.Paste")
			(net "PVDDCR_CPU0_P0_VCCS")
		)
		(pad "2" smd circle
			(at 0.40005 0 270)
			(size 0 0)
			(layers "F.Cu" "F.Mask" "F.Paste")
			(net "GND")
		)
	)
	(footprint ""
		(layer "F.Cu")
		(at 437.515 -94.071948 90)
		(property "Reference" "C2024"
			(at 0 0 90)
			(layer "F.SilkS")
			(hide yes)
			(effects
				(font
					(size 1.27 1.27)
				)
			)
		)
		(property "Value" ""
			(at 0 0 90)
			(layer "F.Fab")
			(effects
				(font
					(size 1.27 1.27)
				)
			)
		)
		(duplicate_pad_numbers_are_jumpers no)
		(fp_line
			(start 0.7874 -0.4064)
			(end 0.7874 0.4064)
			(stroke
				(width 0.1524)
				(type default)
			)
			(layer "F.SilkS")
		)
		(fp_line
			(start -0.7874 -0.4064)
			(end 0.7874 -0.4064)
			(stroke
				(width 0.1524)
				(type default)
			)
			(layer "F.SilkS")
		)
		(fp_line
			(start 0.7874 0.4064)
			(end -0.7874 0.4064)
			(stroke
				(width 0.1524)
				(type default)
			)
			(layer "F.SilkS")
		)
		(fp_line
			(start -0.7874 0.4064)
			(end -0.7874 -0.4064)
			(stroke
				(width 0.1524)
				(type default)
			)
			(layer "F.SilkS")
		)
		(fp_line
			(start -0.12065 -0.305054)
			(end -0.12065 -0.2794)
			(stroke
				(width 0.1)
				(type default)
			)
			(layer "F.Fab")
		)
		(fp_line
			(start -0.67945 -0.305054)
			(end -0.12065 -0.305054)
			(stroke
				(width 0.1)
				(type default)
			)
			(layer "F.Fab")
		)
		(fp_line
			(start 0.67945 -0.3048)
			(end 0.67945 0.3048)
			(stroke
				(width 0.1)
				(type default)
			)
			(layer "F.Fab")
		)
		(fp_line
			(start 0.12065 -0.3048)
			(end 0.67945 -0.3048)
			(stroke
				(width 0.1)
				(type default)
			)
			(layer "F.Fab")
		)
		(fp_line
			(start 0.12065 -0.2794)
			(end 0.12065 -0.3048)
			(stroke
				(width 0.1)
				(type default)
			)
			(layer "F.Fab")
		)
		(fp_line
			(start -0.12065 -0.2794)
			(end 0.12065 -0.2794)
			(stroke
				(width 0.1)
				(type default)
			)
			(layer "F.Fab")
		)
		(fp_line
			(start 0.120396 0.2794)
			(end -0.12065 0.2794)
			(stroke
				(width 0.1)
				(type default)
			)
			(layer "F.Fab")
		)
		(fp_line
			(start -0.12065 0.2794)
			(end -0.12065 0.3048)
			(stroke
				(width 0.1)
				(type default)
			)
			(layer "F.Fab")
		)
		(fp_line
			(start 0.67945 0.3048)
			(end 0.120396 0.3048)
			(stroke
				(width 0.1)
				(type default)
			)
			(layer "F.Fab")
		)
		(fp_line
			(start 0.120396 0.3048)
			(end 0.120396 0.2794)
			(stroke
				(width 0.1)
				(type default)
			)
			(layer "F.Fab")
		)
		(fp_line
			(start -0.12065 0.3048)
			(end -0.67945 0.3048)
			(stroke
				(width 0.1)
				(type default)
			)
			(layer "F.Fab")
		)
		(fp_line
			(start -0.67945 0.3048)
			(end -0.67945 -0.305054)
			(stroke
				(width 0.1)
				(type default)
			)
			(layer "F.Fab")
		)
		(pad "1" smd circle
			(at -0.40005 0 90)
			(size 0 0)
			(layers "F.Cu" "F.Mask" "F.Paste")
			(net "P3V3_OCP_SFF_R")
		)
		(pad "2" smd circle
			(at 0.40005 0 90)
			(size 0 0)
			(layers "F.Cu" "F.Mask" "F.Paste")
			(net "GND")
		)
	)
)
